(kicad_pcb
	(version 20260206)
	(generator "pcbnew")
	(generator_version "10.0")
	(general
		(thickness 1.6)
		(legacy_teardrops no)
	)
	(paper "A4")
	(title_block
		(title "04192023_DAF0TMB3IC0_F0TG_MB_C_brd_V02_OCP.brd")
		(comment 1 "Grand Teton / footprints 7371-7376 of 8354")
	)
	(layers
		(0 "F.Cu" signal "TOP")
		(4 "In1.Cu" signal "GND")
		(6 "In2.Cu" signal "IN1")
		(8 "In3.Cu" signal "GND1")
		(10 "In4.Cu" signal "IN2")
		(12 "In5.Cu" signal "GND2")
		(14 "In6.Cu" signal "IN3")
		(16 "In7.Cu" signal "GND3")
		(18 "In8.Cu" signal "VCC")
		(20 "In9.Cu" signal "VCC1")
		(22 "In10.Cu" signal "GND4")
		(24 "In11.Cu" signal "IN4")
		(26 "In12.Cu" signal "GND5")
		(28 "In13.Cu" signal "IN5")
		(30 "In14.Cu" signal "GND6")
		(32 "In15.Cu" signal "IN6")
		(34 "In16.Cu" signal "GND7")
		(2 "B.Cu" signal "BOTTOM")
		(9 "F.Adhes" user "F.Adhesive")
		(11 "B.Adhes" user "B.Adhesive")
		(13 "F.Paste" user "Package Geometry/Pastemask Top")
		(15 "B.Paste" user "Package Geometry/Pastemask Bottom")
		(5 "F.SilkS" user "Ref Des/Silkscreen Top")
		(7 "B.SilkS" user "Ref Des/Silkscreen Bottom")
		(1 "F.Mask" user "Board Geometry/Soldermask Top")
		(3 "B.Mask" user "Board Geometry/Soldermask Bottom")
		(17 "Dwgs.User" user "User.Drawings")
		(19 "Cmts.User" user "User.Comments")
		(21 "Eco1.User" user "User.Eco1")
		(23 "Eco2.User" user "User.Eco2")
		(25 "Edge.Cuts" user "Board Geometry/Outline")
		(27 "Margin" user)
		(31 "F.CrtYd" user "Package Geometry/Place Bound Top")
		(29 "B.CrtYd" user "Package Geometry/Place Bound Bottom")
		(35 "F.Fab" user "Ref Des/Assembly Top")
		(33 "B.Fab" user "Ref Des/Assembly Bottom")
	)
	(footprint ""
		(layer "B.Cu")
		(at 160.103312 -417.50488 180)
		(property "Reference" "U43"
			(at -0.04318 -3.007106 0)
			(unlocked yes)
			(layer "B.SilkS")
			(effects
				(font
					(size 0.7874 0.5842)
					(thickness 0.1524)
				)
				(justify mirror)
			)
		)
		(property "Value" ""
			(at 0 0 0)
			(layer "B.Fab")
			(effects
				(font
					(size 1.27 1.27)
				)
				(justify mirror)
			)
		)
		(duplicate_pad_numbers_are_jumpers no)
		(fp_line
			(start 1.03378 1.284478)
			(end 1.03378 -1.284478)
			(stroke
				(width 0.1524)
				(type default)
			)
			(layer "B.SilkS")
		)
		(fp_line
			(start 1.03378 -1.284478)
			(end -1.03378 -1.284478)
			(stroke
				(width 0.1524)
				(type default)
			)
			(layer "B.SilkS")
		)
		(fp_line
			(start -1.03378 1.284478)
			(end 1.03378 1.284478)
			(stroke
				(width 0.1524)
				(type default)
			)
			(layer "B.SilkS")
		)
		(fp_line
			(start -1.03378 -1.284478)
			(end -1.03378 1.284478)
			(stroke
				(width 0.1524)
				(type default)
			)
			(layer "B.SilkS")
		)
		(fp_poly
			(pts
				(xy 1.183132 -0.700532) (xy 1.6129 -0.178308) (xy 1.858772 -0.731012)
			)
			(stroke
				(width 0)
				(type default)
			)
			(fill yes)
			(layer "B.SilkS")
		)
		(fp_line
			(start 0.774954 1.02489)
			(end 0.774954 -1.02489)
			(stroke
				(width 0.1)
				(type default)
			)
			(layer "B.Fab")
		)
		(fp_line
			(start 0.774954 -1.02489)
			(end -0.774954 -1.02489)
			(stroke
				(width 0.1)
				(type default)
			)
			(layer "B.Fab")
		)
		(fp_line
			(start -0.774954 1.02489)
			(end 0.774954 1.02489)
			(stroke
				(width 0.1)
				(type default)
			)
			(layer "B.Fab")
		)
		(fp_line
			(start -0.774954 -1.02489)
			(end -0.774954 1.02489)
			(stroke
				(width 0.1)
				(type default)
			)
			(layer "B.Fab")
		)
		(fp_poly
			(pts
				(xy 1.201674 -0.750062) (xy 1.806702 -0.447548) (xy 1.806702 -1.052576)
			)
			(stroke
				(width 0)
				(type default)
			)
			(fill yes)
			(layer "B.Fab")
		)
		(pad "1" smd rect
			(at 0.64008 -0.750062 270)
			(size 0.3048 0.5334)
			(layers "B.Cu" "B.Mask" "B.Paste")
			(net "SMB_RT_CPU1_P2_ROM_MUX_1D_SCL")
		)
		(pad "2" smd rect
			(at 0.64008 -0.249936 270)
			(size 0.254 0.5334)
			(layers "B.Cu" "B.Mask" "B.Paste")
			(net "SMB_RT_CPU1_P2_ROM_MUX_1D_SDA")
		)
		(pad "3" smd rect
			(at 0.64008 0.249936 270)
			(size 0.254 0.5334)
			(layers "B.Cu" "B.Mask" "B.Paste")
			(net "SMB_RT_CPU1_P2_ROM_MUX_2D_SCL")
		)
		(pad "4" smd rect
			(at 0.64008 0.750062 270)
			(size 0.3048 0.5334)
			(layers "B.Cu" "B.Mask" "B.Paste")
			(net "SMB_RT_CPU1_P2_ROM_MUX_2D_SDA")
		)
		(pad "5" smd rect
			(at 0 0.839978)
			(size 0.3302 0.635)
			(layers "B.Cu" "B.Mask" "B.Paste")
			(net "GND")
		)
		(pad "6" smd rect
			(at -0.64008 0.750062 270)
			(size 0.3048 0.5334)
			(layers "B.Cu" "B.Mask" "B.Paste")
			(net "RT_ROM_MUX4_OE_N")
		)
		(pad "7" smd rect
			(at -0.64008 0.249936 270)
			(size 0.254 0.5334)
			(layers "B.Cu" "B.Mask" "B.Paste")
			(net "SMB_RT_CPU1_P2_ROM_R_SDA")
		)
		(pad "8" smd rect
			(at -0.64008 -0.249936 270)
			(size 0.254 0.5334)
			(layers "B.Cu" "B.Mask" "B.Paste")
			(net "SMB_RT_CPU1_P2_ROM_R_SCL")
		)
		(pad "9" smd rect
			(at -0.64008 -0.750062 270)
			(size 0.3048 0.5334)
			(layers "B.Cu" "B.Mask" "B.Paste")
			(net "FM_SMB_RT_ROM_MUX4_SEL")
		)
		(pad "10" smd rect
			(at 0 -0.839978)
			(size 0.3302 0.635)
			(layers "B.Cu" "B.Mask" "B.Paste")
			(net "P3V3_AUX")
		)
	)
	(footprint ""
		(layer "B.Cu")
		(at 258.208018 -53.118512 90)
		(property "Reference" "PR4541"
			(at 0 0 90)
			(layer "B.SilkS")
			(hide yes)
			(effects
				(font
					(size 1.27 1.27)
				)
				(justify mirror)
			)
		)
		(property "Value" ""
			(at 0 0 90)
			(layer "B.Fab")
			(effects
				(font
					(size 1.27 1.27)
				)
				(justify mirror)
			)
		)
		(duplicate_pad_numbers_are_jumpers no)
		(fp_line
			(start 0.7874 -0.4064)
			(end -0.7874 -0.4064)
			(stroke
				(width 0.1524)
				(type default)
			)
			(layer "B.SilkS")
		)
		(fp_line
			(start -0.7874 -0.4064)
			(end -0.7874 0.4064)
			(stroke
				(width 0.1524)
				(type default)
			)
			(layer "B.SilkS")
		)
		(fp_line
			(start 0.7874 0.4064)
			(end 0.7874 -0.4064)
			(stroke
				(width 0.1524)
				(type default)
			)
			(layer "B.SilkS")
		)
		(fp_line
			(start -0.7874 0.4064)
			(end 0.7874 0.4064)
			(stroke
				(width 0.1524)
				(type default)
			)
			(layer "B.SilkS")
		)
		(fp_line
			(start 0.67945 -0.305054)
			(end 0.12065 -0.305054)
			(stroke
				(width 0.1)
				(type default)
			)
			(layer "B.Fab")
		)
		(fp_line
			(start 0.12065 -0.305054)
			(end 0.12065 -0.2794)
			(stroke
				(width 0.1)
				(type default)
			)
			(layer "B.Fab")
		)
		(fp_line
			(start -0.12065 -0.3048)
			(end -0.67945 -0.3048)
			(stroke
				(width 0.1)
				(type default)
			)
			(layer "B.Fab")
		)
		(fp_line
			(start -0.67945 -0.3048)
			(end -0.67945 0.3048)
			(stroke
				(width 0.1)
				(type default)
			)
			(layer "B.Fab")
		)
		(fp_line
			(start 0.12065 -0.2794)
			(end -0.12065 -0.2794)
			(stroke
				(width 0.1)
				(type default)
			)
			(layer "B.Fab")
		)
		(fp_line
			(start -0.12065 -0.2794)
			(end -0.12065 -0.3048)
			(stroke
				(width 0.1)
				(type default)
			)
			(layer "B.Fab")
		)
		(fp_line
			(start 0.12065 0.2794)
			(end 0.12065 0.3048)
			(stroke
				(width 0.1)
				(type default)
			)
			(layer "B.Fab")
		)
		(fp_line
			(start -0.120396 0.2794)
			(end 0.12065 0.2794)
			(stroke
				(width 0.1)
				(type default)
			)
			(layer "B.Fab")
		)
		(fp_line
			(start 0.67945 0.3048)
			(end 0.67945 -0.305054)
			(stroke
				(width 0.1)
				(type default)
			)
			(layer "B.Fab")
		)
		(fp_line
			(start 0.12065 0.3048)
			(end 0.67945 0.3048)
			(stroke
				(width 0.1)
				(type default)
			)
			(layer "B.Fab")
		)
		(fp_line
			(start -0.120396 0.3048)
			(end -0.120396 0.2794)
			(stroke
				(width 0.1)
				(type default)
			)
			(layer "B.Fab")
		)
		(fp_line
			(start -0.67945 0.3048)
			(end -0.120396 0.3048)
			(stroke
				(width 0.1)
				(type default)
			)
			(layer "B.Fab")
		)
		(pad "1" smd circle
			(at 0.40005 0 270)
			(size 0 0)
			(layers "B.Cu" "B.Mask" "B.Paste")
			(net "P12V_E1S_ISET_0")
		)
		(pad "2" smd circle
			(at -0.40005 0 270)
			(size 0 0)
			(layers "B.Cu" "B.Mask" "B.Paste")
			(net "P12V_E1S_ISET_0_R")
		)
	)
	(footprint ""
		(layer "B.Cu")
		(at 347.008958 -250.89231 180)
		(property "Reference" "C2521"
			(at 0 0 0)
			(layer "B.SilkS")
			(hide yes)
			(effects
				(font
					(size 1.27 1.27)
				)
				(justify mirror)
			)
		)
		(property "Value" ""
			(at 0 0 0)
			(layer "B.Fab")
			(effects
				(font
					(size 1.27 1.27)
				)
				(justify mirror)
			)
		)
		(duplicate_pad_numbers_are_jumpers no)
		(fp_line
			(start 0.7874 0.4064)
			(end 0.7874 -0.4064)
			(stroke
				(width 0.1524)
				(type default)
			)
			(layer "B.SilkS")
		)
		(fp_line
			(start 0.7874 -0.4064)
			(end -0.7874 -0.4064)
			(stroke
				(width 0.1524)
				(type default)
			)
			(layer "B.SilkS")
		)
		(fp_line
			(start -0.7874 0.4064)
			(end 0.7874 0.4064)
			(stroke
				(width 0.1524)
				(type default)
			)
			(layer "B.SilkS")
		)
		(fp_line
			(start -0.7874 -0.4064)
			(end -0.7874 0.4064)
			(stroke
				(width 0.1524)
				(type default)
			)
			(layer "B.SilkS")
		)
		(fp_line
			(start 0.67945 0.3048)
			(end 0.67945 -0.305054)
			(stroke
				(width 0.1)
				(type default)
			)
			(layer "B.Fab")
		)
		(fp_line
			(start 0.67945 -0.305054)
			(end 0.12065 -0.305054)
			(stroke
				(width 0.1)
				(type default)
			)
			(layer "B.Fab")
		)
		(fp_line
			(start 0.12065 0.3048)
			(end 0.67945 0.3048)
			(stroke
				(width 0.1)
				(type default)
			)
			(layer "B.Fab")
		)
		(fp_line
			(start 0.12065 0.2794)
			(end 0.12065 0.3048)
			(stroke
				(width 0.1)
				(type default)
			)
			(layer "B.Fab")
		)
		(fp_line
			(start 0.12065 -0.2794)
			(end -0.12065 -0.2794)
			(stroke
				(width 0.1)
				(type default)
			)
			(layer "B.Fab")
		)
		(fp_line
			(start 0.12065 -0.305054)
			(end 0.12065 -0.2794)
			(stroke
				(width 0.1)
				(type default)
			)
			(layer "B.Fab")
		)
		(fp_line
			(start -0.120396 0.3048)
			(end -0.120396 0.2794)
			(stroke
				(width 0.1)
				(type default)
			)
			(layer "B.Fab")
		)
		(fp_line
			(start -0.120396 0.2794)
			(end 0.12065 0.2794)
			(stroke
				(width 0.1)
				(type default)
			)
			(layer "B.Fab")
		)
		(fp_line
			(start -0.12065 -0.2794)
			(end -0.12065 -0.3048)
			(stroke
				(width 0.1)
				(type default)
			)
			(layer "B.Fab")
		)
		(fp_line
			(start -0.12065 -0.3048)
			(end -0.67945 -0.3048)
			(stroke
				(width 0.1)
				(type default)
			)
			(layer "B.Fab")
		)
		(fp_line
			(start -0.67945 0.3048)
			(end -0.120396 0.3048)
			(stroke
				(width 0.1)
				(type default)
			)
			(layer "B.Fab")
		)
		(fp_line
			(start -0.67945 -0.3048)
			(end -0.67945 0.3048)
			(stroke
				(width 0.1)
				(type default)
			)
			(layer "B.Fab")
		)
		(pad "1" smd circle
			(at 0.40005 0)
			(size 0 0)
			(layers "B.Cu" "B.Mask" "B.Paste")
			(net "PVDD18_S5_P0")
		)
		(pad "2" smd circle
			(at -0.40005 0)
			(size 0 0)
			(layers "B.Cu" "B.Mask" "B.Paste")
			(net "GND")
		)
	)
	(footprint ""
		(layer "B.Cu")
		(at 419.129464 -426.799248 180)
		(property "Reference" "R840"
			(at 0 0 0)
			(layer "B.SilkS")
			(hide yes)
			(effects
				(font
					(size 1.27 1.27)
				)
				(justify mirror)
			)
		)
		(property "Value" ""
			(at 0 0 0)
			(layer "B.Fab")
			(effects
				(font
					(size 1.27 1.27)
				)
				(justify mirror)
			)
		)
		(duplicate_pad_numbers_are_jumpers no)
		(fp_line
			(start 0.32512 0.175006)
			(end 0.32512 -0.175006)
			(stroke
				(width 0.1)
				(type default)
			)
			(layer "B.Fab")
		)
		(fp_line
			(start 0.32512 -0.175006)
			(end -0.32512 -0.175006)
			(stroke
				(width 0.1)
				(type default)
			)
			(layer "B.Fab")
		)
		(fp_line
			(start -0.32512 0.175006)
			(end 0.32512 0.175006)
			(stroke
				(width 0.1)
				(type default)
			)
			(layer "B.Fab")
		)
		(fp_line
			(start -0.32512 -0.175006)
			(end -0.32512 0.175006)
			(stroke
				(width 0.1)
				(type default)
			)
			(layer "B.Fab")
		)
		(pad "1" smd rect
			(at 0.2667 0)
			(size 0.3048 0.381)
			(layers "B.Cu" "B.Mask" "B.Paste")
			(net "P1V8_CPU0_RT_1D")
		)
		(pad "2" smd rect
			(at -0.2667 0 180)
			(size 0.3048 0.381)
			(layers "B.Cu" "B.Mask" "B.Paste")
			(net "SMB_RT_CPU0_P2_ROM_R_SDA")
		)
	)
	(footprint ""
		(layer "B.Cu")
		(at 350.342454 -256.73431 180)
		(property "Reference" "C2554"
			(at 0 0 0)
			(layer "B.SilkS")
			(hide yes)
			(effects
				(font
					(size 1.27 1.27)
				)
				(justify mirror)
			)
		)
		(property "Value" ""
			(at 0 0 0)
			(layer "B.Fab")
			(effects
				(font
					(size 1.27 1.27)
				)
				(justify mirror)
			)
		)
		(duplicate_pad_numbers_are_jumpers no)
		(fp_line
			(start 0.7874 0.4064)
			(end 0.7874 -0.4064)
			(stroke
				(width 0.1524)
				(type default)
			)
			(layer "B.SilkS")
		)
		(fp_line
			(start 0.7874 -0.4064)
			(end -0.7874 -0.4064)
			(stroke
				(width 0.1524)
				(type default)
			)
			(layer "B.SilkS")
		)
		(fp_line
			(start -0.7874 0.4064)
			(end 0.7874 0.4064)
			(stroke
				(width 0.1524)
				(type default)
			)
			(layer "B.SilkS")
		)
		(fp_line
			(start -0.7874 -0.4064)
			(end -0.7874 0.4064)
			(stroke
				(width 0.1524)
				(type default)
			)
			(layer "B.SilkS")
		)
		(fp_line
			(start 0.67945 0.3048)
			(end 0.67945 -0.305054)
			(stroke
				(width 0.1)
				(type default)
			)
			(layer "B.Fab")
		)
		(fp_line
			(start 0.67945 -0.305054)
			(end 0.12065 -0.305054)
			(stroke
				(width 0.1)
				(type default)
			)
			(layer "B.Fab")
		)
		(fp_line
			(start 0.12065 0.3048)
			(end 0.67945 0.3048)
			(stroke
				(width 0.1)
				(type default)
			)
			(layer "B.Fab")
		)
		(fp_line
			(start 0.12065 0.2794)
			(end 0.12065 0.3048)
			(stroke
				(width 0.1)
				(type default)
			)
			(layer "B.Fab")
		)
		(fp_line
			(start 0.12065 -0.2794)
			(end -0.12065 -0.2794)
			(stroke
				(width 0.1)
				(type default)
			)
			(layer "B.Fab")
		)
		(fp_line
			(start 0.12065 -0.305054)
			(end 0.12065 -0.2794)
			(stroke
				(width 0.1)
				(type default)
			)
			(layer "B.Fab")
		)
		(fp_line
			(start -0.120396 0.3048)
			(end -0.120396 0.2794)
			(stroke
				(width 0.1)
				(type default)
			)
			(layer "B.Fab")
		)
		(fp_line
			(start -0.120396 0.2794)
			(end 0.12065 0.2794)
			(stroke
				(width 0.1)
				(type default)
			)
			(layer "B.Fab")
		)
		(fp_line
			(start -0.12065 -0.2794)
			(end -0.12065 -0.3048)
			(stroke
				(width 0.1)
				(type default)
			)
			(layer "B.Fab")
		)
		(fp_line
			(start -0.12065 -0.3048)
			(end -0.67945 -0.3048)
			(stroke
				(width 0.1)
				(type default)
			)
			(layer "B.Fab")
		)
		(fp_line
			(start -0.67945 0.3048)
			(end -0.120396 0.3048)
			(stroke
				(width 0.1)
				(type default)
			)
			(layer "B.Fab")
		)
		(fp_line
			(start -0.67945 -0.3048)
			(end -0.67945 0.3048)
			(stroke
				(width 0.1)
				(type default)
			)
			(layer "B.Fab")
		)
		(pad "1" smd circle
			(at 0.40005 0)
			(size 0 0)
			(layers "B.Cu" "B.Mask" "B.Paste")
			(net "PVDDCR_SOC_P0")
		)
		(pad "2" smd circle
			(at -0.40005 0)
			(size 0 0)
			(layers "B.Cu" "B.Mask" "B.Paste")
			(net "GND")
		)
	)
	(footprint ""
		(layer "B.Cu")
		(at 24.765 -358.775 180)
		(property "Reference" "R8219"
			(at 0 0 0)
			(layer "B.SilkS")
			(hide yes)
			(effects
				(font
					(size 1.27 1.27)
				)
				(justify mirror)
			)
		)
		(property "Value" ""
			(at 0 0 0)
			(layer "B.Fab")
			(effects
				(font
					(size 1.27 1.27)
				)
				(justify mirror)
			)
		)
		(duplicate_pad_numbers_are_jumpers no)
		(fp_line
			(start 0.7874 0.4064)
			(end 0.7874 -0.4064)
			(stroke
				(width 0.1524)
				(type default)
			)
			(layer "B.SilkS")
		)
		(fp_line
			(start 0.7874 -0.4064)
			(end -0.7874 -0.4064)
			(stroke
				(width 0.1524)
				(type default)
			)
			(layer "B.SilkS")
		)
		(fp_line
			(start -0.7874 0.4064)
			(end 0.7874 0.4064)
			(stroke
				(width 0.1524)
				(type default)
			)
			(layer "B.SilkS")
		)
		(fp_line
			(start -0.7874 -0.4064)
			(end -0.7874 0.4064)
			(stroke
				(width 0.1524)
				(type default)
			)
			(layer "B.SilkS")
		)
		(fp_line
			(start 0.67945 0.3048)
			(end 0.67945 -0.305054)
			(stroke
				(width 0.1)
				(type default)
			)
			(layer "B.Fab")
		)
		(fp_line
			(start 0.67945 -0.305054)
			(end 0.12065 -0.305054)
			(stroke
				(width 0.1)
				(type default)
			)
			(layer "B.Fab")
		)
		(fp_line
			(start 0.12065 0.3048)
			(end 0.67945 0.3048)
			(stroke
				(width 0.1)
				(type default)
			)
			(layer "B.Fab")
		)
		(fp_line
			(start 0.12065 0.2794)
			(end 0.12065 0.3048)
			(stroke
				(width 0.1)
				(type default)
			)
			(layer "B.Fab")
		)
		(fp_line
			(start 0.12065 -0.2794)
			(end -0.12065 -0.2794)
			(stroke
				(width 0.1)
				(type default)
			)
			(layer "B.Fab")
		)
		(fp_line
			(start 0.12065 -0.305054)
			(end 0.12065 -0.2794)
			(stroke
				(width 0.1)
				(type default)
			)
			(layer "B.Fab")
		)
		(fp_line
			(start -0.120396 0.3048)
			(end -0.120396 0.2794)
			(stroke
				(width 0.1)
				(type default)
			)
			(layer "B.Fab")
		)
		(fp_line
			(start -0.120396 0.2794)
			(end 0.12065 0.2794)
			(stroke
				(width 0.1)
				(type default)
			)
			(layer "B.Fab")
		)
		(fp_line
			(start -0.12065 -0.2794)
			(end -0.12065 -0.3048)
			(stroke
				(width 0.1)
				(type default)
			)
			(layer "B.Fab")
		)
		(fp_line
			(start -0.12065 -0.3048)
			(end -0.67945 -0.3048)
			(stroke
				(width 0.1)
				(type default)
			)
			(layer "B.Fab")
		)
		(fp_line
			(start -0.67945 0.3048)
			(end -0.120396 0.3048)
			(stroke
				(width 0.1)
				(type default)
			)
			(layer "B.Fab")
		)
		(fp_line
			(start -0.67945 -0.3048)
			(end -0.67945 0.3048)
			(stroke
				(width 0.1)
				(type default)
			)
			(layer "B.Fab")
		)
		(pad "1" smd circle
			(at 0.40005 0)
			(size 0 0)
			(layers "B.Cu" "B.Mask" "B.Paste")
			(net "SVID_PVDDCR_CPU1_P1_SVTO")
		)
		(pad "2" smd circle
			(at -0.40005 0)
			(size 0 0)
			(layers "B.Cu" "B.Mask" "B.Paste")
			(net "GND")
		)
	)
)
